# S9S_MB_2U (Grand Teton) — schematic netlist excerpt (pin names and nets, part order shuffled) for the footprints in the layout excerpt that follows; sources: Cadence DE-HDL packaged netlist, KiCad conversion of 03242023_DA0F0TMBIJ0_F0T_Motherboard_J_brd_V01_OCP.brd

PC474  Q_CAP  0.1UF 25V 10% X7R  pkg 0402  page 292 : A = PVCCINFAON_CPU1_VIN_CSNIN ; B = GND
PC2164  Q_CAP  0.22UF 16V 10% X7R  pkg 0402  page 163 : A = P12V_OCP_TIMER_2 ; B = GND

(kicad_pcb
	(version 20260206)
	(generator "pcbnew")
	(generator_version "10.0")
	(general
		(thickness 1.6)
		(legacy_teardrops no)
	)
	(paper "A4")
	(title_block
		(title "03242023_DA0F0TMBIJ0_F0T_Motherboard_J_brd_V01_OCP.brd")
		(comment 1 "Grand Teton / footprints 982-983 of 6105")
	)
	(layers
		(0 "F.Cu" signal "TOP")
		(4 "In1.Cu" signal "GND")
		(6 "In2.Cu" signal "IN1")
		(8 "In3.Cu" signal "GND1")
		(10 "In4.Cu" signal "IN2")
		(12 "In5.Cu" signal "GND2")
		(14 "In6.Cu" signal "IN3")
		(16 "In7.Cu" signal "GND3")
		(18 "In8.Cu" signal "VCC")
		(20 "In9.Cu" signal "VCC1")
		(22 "In10.Cu" signal "GND4")
		(24 "In11.Cu" signal "IN4")
		(26 "In12.Cu" signal "GND5")
		(28 "In13.Cu" signal "IN5")
		(30 "In14.Cu" signal "GND6")
		(32 "In15.Cu" signal "IN6")
		(34 "In16.Cu" signal "GND7")
		(2 "B.Cu" signal "BOTTOM")
		(9 "F.Adhes" user "F.Adhesive")
		(11 "B.Adhes" user "B.Adhesive")
		(13 "F.Paste" user "Package Geometry/Pastemask Top")
		(15 "B.Paste" user "Package Geometry/Pastemask Bottom")
		(5 "F.SilkS" user "Ref Des/Silkscreen Top")
		(7 "B.SilkS" user "Ref Des/Silkscreen Bottom")
		(1 "F.Mask" user "Board Geometry/Soldermask Top")
		(3 "B.Mask" user "Board Geometry/Soldermask Bottom")
		(17 "Dwgs.User" user "User.Drawings")
		(19 "Cmts.User" user "User.Comments")
		(21 "Eco1.User" user "User.Eco1")
		(23 "Eco2.User" user "User.Eco2")
		(25 "Edge.Cuts" user "Board Geometry/Outline")
		(27 "Margin" user)
		(31 "F.CrtYd" user "Package Geometry/Place Bound Top")
		(29 "B.CrtYd" user "Package Geometry/Place Bound Bottom")
		(35 "F.Fab" user "Ref Des/Assembly Top")
		(33 "B.Fab" user "Ref Des/Assembly Bottom")
	)
	(footprint ""
		(layer "F.Cu")
		(at 27.0383 -128.364996 180)
		(property "Reference" "PC474"
			(at 0 0 180)
			(layer "F.SilkS")
			(hide yes)
			(effects
				(font
					(size 1.27 1.27)
				)
			)
		)
		(property "Value" ""
			(at 0 0 180)
			(layer "F.Fab")
			(effects
				(font
					(size 1.27 1.27)
				)
			)
		)
		(duplicate_pad_numbers_are_jumpers no)
		(fp_line
			(start 0.7874 0.4064)
			(end -0.7874 0.4064)
			(stroke
				(width 0.1524)
				(type default)
			)
			(layer "F.SilkS")
		)
		(fp_line
			(start 0.7874 -0.4064)
			(end 0.7874 0.4064)
			(stroke
				(width 0.1524)
				(type default)
			)
			(layer "F.SilkS")
		)
		(fp_line
			(start -0.7874 0.4064)
			(end -0.7874 -0.4064)
			(stroke
				(width 0.1524)
				(type default)
			)
			(layer "F.SilkS")
		)
		(fp_line
			(start -0.7874 -0.4064)
			(end 0.7874 -0.4064)
			(stroke
				(width 0.1524)
				(type default)
			)
			(layer "F.SilkS")
		)
		(fp_line
			(start 0.67945 0.3048)
			(end 0.120396 0.3048)
			(stroke
				(width 0.1)
				(type default)
			)
			(layer "F.Fab")
		)
		(fp_line
			(start 0.67945 -0.3048)
			(end 0.67945 0.3048)
			(stroke
				(width 0.1)
				(type default)
			)
			(layer "F.Fab")
		)
		(fp_line
			(start 0.12065 -0.2794)
			(end 0.12065 -0.3048)
			(stroke
				(width 0.1)
				(type default)
			)
			(layer "F.Fab")
		)
		(fp_line
			(start 0.12065 -0.3048)
			(end 0.67945 -0.3048)
			(stroke
				(width 0.1)
				(type default)
			)
			(layer "F.Fab")
		)
		(fp_line
			(start 0.120396 0.3048)
			(end 0.120396 0.2794)
			(stroke
				(width 0.1)
				(type default)
			)
			(layer "F.Fab")
		)
		(fp_line
			(start 0.120396 0.2794)
			(end -0.12065 0.2794)
			(stroke
				(width 0.1)
				(type default)
			)
			(layer "F.Fab")
		)
		(fp_line
			(start -0.12065 0.3048)
			(end -0.67945 0.3048)
			(stroke
				(width 0.1)
				(type default)
			)
			(layer "F.Fab")
		)
		(fp_line
			(start -0.12065 0.2794)
			(end -0.12065 0.3048)
			(stroke
				(width 0.1)
				(type default)
			)
			(layer "F.Fab")
		)
		(fp_line
			(start -0.12065 -0.2794)
			(end 0.12065 -0.2794)
			(stroke
				(width 0.1)
				(type default)
			)
			(layer "F.Fab")
		)
		(fp_line
			(start -0.12065 -0.305054)
			(end -0.12065 -0.2794)
			(stroke
				(width 0.1)
				(type default)
			)
			(layer "F.Fab")
		)
		(fp_line
			(start -0.67945 0.3048)
			(end -0.67945 -0.305054)
			(stroke
				(width 0.1)
				(type default)
			)
			(layer "F.Fab")
		)
		(fp_line
			(start -0.67945 -0.305054)
			(end -0.12065 -0.305054)
			(stroke
				(width 0.1)
				(type default)
			)
			(layer "F.Fab")
		)
		(pad "1" smd circle
			(at -0.40005 0 180)
			(size 0 0)
			(layers "F.Cu" "F.Mask" "F.Paste")
			(net "PVCCINFAON_CPU1_VIN_CSNIN")
		)
		(pad "2" smd circle
			(at 0.40005 0 180)
			(size 0 0)
			(layers "F.Cu" "F.Mask" "F.Paste")
			(net "GND")
		)
	)
	(footprint ""
		(layer "F.Cu")
		(at 69.036438 -31.887922 90)
		(property "Reference" "PC2164"
			(at 0 0 90)
			(layer "F.SilkS")
			(hide yes)
			(effects
				(font
					(size 1.27 1.27)
				)
			)
		)
		(property "Value" ""
			(at 0 0 90)
			(layer "F.Fab")
			(effects
				(font
					(size 1.27 1.27)
				)
			)
		)
		(duplicate_pad_numbers_are_jumpers no)
		(fp_line
			(start 0.7874 -0.4064)
			(end 0.7874 0.4064)
			(stroke
				(width 0.1524)
				(type default)
			)
			(layer "F.SilkS")
		)
		(fp_line
			(start -0.7874 -0.4064)
			(end 0.7874 -0.4064)
			(stroke
				(width 0.1524)
				(type default)
			)
			(layer "F.SilkS")
		)
		(fp_line
			(start 0.7874 0.4064)
			(end -0.7874 0.4064)
			(stroke
				(width 0.1524)
				(type default)
			)
			(layer "F.SilkS")
		)
		(fp_line
			(start -0.7874 0.4064)
			(end -0.7874 -0.4064)
			(stroke
				(width 0.1524)
				(type default)
			)
			(layer "F.SilkS")
		)
		(fp_line
			(start -0.12065 -0.305054)
			(end -0.12065 -0.2794)
			(stroke
				(width 0.1)
				(type default)
			)
			(layer "F.Fab")
		)
		(fp_line
			(start -0.67945 -0.305054)
			(end -0.12065 -0.305054)
			(stroke
				(width 0.1)
				(type default)
			)
			(layer "F.Fab")
		)
		(fp_line
			(start 0.67945 -0.3048)
			(end 0.67945 0.3048)
			(stroke
				(width 0.1)
				(type default)
			)
			(layer "F.Fab")
		)
		(fp_line
			(start 0.12065 -0.3048)
			(end 0.67945 -0.3048)
			(stroke
				(width 0.1)
				(type default)
			)
			(layer "F.Fab")
		)
		(fp_line
			(start 0.12065 -0.2794)
			(end 0.12065 -0.3048)
			(stroke
				(width 0.1)
				(type default)
			)
			(layer "F.Fab")
		)
		(fp_line
			(start -0.12065 -0.2794)
			(end 0.12065 -0.2794)
			(stroke
				(width 0.1)
				(type default)
			)
			(layer "F.Fab")
		)
		(fp_line
			(start 0.120396 0.2794)
			(end -0.12065 0.2794)
			(stroke
				(width 0.1)
				(type default)
			)
			(layer "F.Fab")
		)
		(fp_line
			(start -0.12065 0.2794)
			(end -0.12065 0.3048)
			(stroke
				(width 0.1)
				(type default)
			)
			(layer "F.Fab")
		)
		(fp_line
			(start 0.67945 0.3048)
			(end 0.120396 0.3048)
			(stroke
				(width 0.1)
				(type default)
			)
			(layer "F.Fab")
		)
		(fp_line
			(start 0.120396 0.3048)
			(end 0.120396 0.2794)
			(stroke
				(width 0.1)
				(type default)
			)
			(layer "F.Fab")
		)
		(fp_line
			(start -0.12065 0.3048)
			(end -0.67945 0.3048)
			(stroke
				(width 0.1)
				(type default)
			)
			(layer "F.Fab")
		)
		(fp_line
			(start -0.67945 0.3048)
			(end -0.67945 -0.305054)
			(stroke
				(width 0.1)
				(type default)
			)
			(layer "F.Fab")
		)
		(pad "1" smd circle
			(at -0.40005 0 90)
			(size 0 0)
			(layers "F.Cu" "F.Mask" "F.Paste")
			(net "P12V_OCP_TIMER_2")
		)
		(pad "2" smd circle
			(at 0.40005 0 90)
			(size 0 0)
			(layers "F.Cu" "F.Mask" "F.Paste")
			(net "GND")
		)
	)
)
